FILE_TYPE = MULTI_PHYS_TABLE;

PART 'SN74LVC2G07DCKR'

{========================================================================================}
:VALUE             | PACK_TYPE | MATERIAL | PART_NUMBER       = STANDARD        | LIFECYCLE      | ENVCOMP | PART_NUMBER       | JEDEC_TYPE | CLASS | DESCRIPTION                           | HEIGHT   | COMPONENT_TYPE | LEAD_LENGTH | LPID | STATUS | RPL | AML | MANUF_PN          | DAY        ;
{========================================================================================}
 'SN74LVC2G07DCKR' | 'SMLF'    | 'IC'     | 'AL002G07006'(!)  = 'End of Design' | 'Comp-Approve' | 'NO'    | 'AL002G07006'     |'SC70-6'| 'IC'  | 'IC(6P) SN74LVC2G07DCKR(SC70-6)'      | '.044IN' | ''             | ''          | ''   | ''     | ''  | ''  | 'SN74LVC2G07DCKR' | '20101228'
 'SN74LVC2G07DCKR' | 'SMLF'    | 'EMPTY'  | 'AL002G07006'(!)  = 'End of Design' | 'Comp-Approve' | 'NO'    | 'AL002G07006'     |'SC70-6'| 'IO'  | 'IC(6P) SN74LVC2G07DCKR(SC70-6)'      | '.044IN' | ''             | ''          | ''   | ''     | ''  | ''  | 'SN74LVC2G07DCKR' | '20101228'
 'SN74LVC2G07DCKR' | 'SMLF'    | 'IC'     | 'AL002G07006SEL1'(!) = ''              | ''               | ''      | 'AL002G07006SEL1' |'SC70-6'| 'IC'  | 'IC OTHER(6P) SN74LVC2G07DCKR SELASN' | ''       | ''             | ''          | ''   | ''     | ''  | ''  | 'SN74LVC2G07DCKR' | '20230719'
 'SN74LVC2G07DCKR' | 'SMLF'    | 'EMPTY'  | 'AL002G07006SEL1'(!) = ''              | ''               | ''      | 'AL002G07006SEL1' |'SC70-6'| 'IO'  | 'IC OTHER(6P) SN74LVC2G07DCKR SELASN' | ''       | ''             | ''          | ''   | ''     | ''  | ''  | 'SN74LVC2G07DCKR' | '20230719'

END_PART

END.

